(kicad_pcb
	(version 20260206)
	(generator "pcbnew")
	(generator_version "10.0")
	(general
		(thickness 1.6)
		(legacy_teardrops no)
	)
	(paper "A4")
	(title_block
		(title "04192023_DAF0TMB3IC0_F0TG_MB_C_brd_V02_OCP.brd")
		(comment 1 "Grand Teton / footprints 3912-3916 of 8354")
	)
	(layers
		(0 "F.Cu" signal "TOP")
		(4 "In1.Cu" signal "GND")
		(6 "In2.Cu" signal "IN1")
		(8 "In3.Cu" signal "GND1")
		(10 "In4.Cu" signal "IN2")
		(12 "In5.Cu" signal "GND2")
		(14 "In6.Cu" signal "IN3")
		(16 "In7.Cu" signal "GND3")
		(18 "In8.Cu" signal "VCC")
		(20 "In9.Cu" signal "VCC1")
		(22 "In10.Cu" signal "GND4")
		(24 "In11.Cu" signal "IN4")
		(26 "In12.Cu" signal "GND5")
		(28 "In13.Cu" signal "IN5")
		(30 "In14.Cu" signal "GND6")
		(32 "In15.Cu" signal "IN6")
		(34 "In16.Cu" signal "GND7")
		(2 "B.Cu" signal "BOTTOM")
		(9 "F.Adhes" user "F.Adhesive")
		(11 "B.Adhes" user "B.Adhesive")
		(13 "F.Paste" user "Package Geometry/Pastemask Top")
		(15 "B.Paste" user "Package Geometry/Pastemask Bottom")
		(5 "F.SilkS" user "Ref Des/Silkscreen Top")
		(7 "B.SilkS" user "Ref Des/Silkscreen Bottom")
		(1 "F.Mask" user "Board Geometry/Soldermask Top")
		(3 "B.Mask" user "Board Geometry/Soldermask Bottom")
		(17 "Dwgs.User" user "User.Drawings")
		(19 "Cmts.User" user "User.Comments")
		(21 "Eco1.User" user "User.Eco1")
		(23 "Eco2.User" user "User.Eco2")
		(25 "Edge.Cuts" user "Board Geometry/Outline")
		(27 "Margin" user)
		(31 "F.CrtYd" user "Package Geometry/Place Bound Top")
		(29 "B.CrtYd" user "Package Geometry/Place Bound Bottom")
		(35 "F.Fab" user "Ref Des/Assembly Top")
		(33 "B.Fab" user "Ref Des/Assembly Bottom")
	)
	(footprint ""
		(layer "F.Cu")
		(at 214.344504 -17.766792 -90)
		(property "Reference" "U90"
			(at -0.832612 -2.35331 90)
			(unlocked yes)
			(layer "F.SilkS")
			(effects
				(font
					(size 0.7874 0.5842)
					(thickness 0.1524)
				)
				(justify left)
			)
		)
		(property "Value" ""
			(at 0 0 270)
			(layer "F.Fab")
			(effects
				(font
					(size 1.27 1.27)
				)
			)
		)
		(duplicate_pad_numbers_are_jumpers no)
		(fp_line
			(start -2.25044 1.5494)
			(end -2.25044 1.3208)
			(stroke
				(width 0.1524)
				(type default)
			)
			(layer "F.SilkS")
		)
		(fp_line
			(start 2.25044 1.5494)
			(end -2.25044 1.5494)
			(stroke
				(width 0.1524)
				(type default)
			)
			(layer "F.SilkS")
		)
		(fp_line
			(start 2.25044 1.3208)
			(end 2.25044 1.5494)
			(stroke
				(width 0.1524)
				(type default)
			)
			(layer "F.SilkS")
		)
		(fp_line
			(start 0 -0.9652)
			(end -0.5842 -1.5494)
			(stroke
				(width 0.1524)
				(type default)
			)
			(layer "F.SilkS")
		)
		(fp_line
			(start 2.25044 -1.3208)
			(end 2.25044 -1.5494)
			(stroke
				(width 0.1524)
				(type default)
			)
			(layer "F.SilkS")
		)
		(fp_line
			(start -2.25044 -1.5494)
			(end -2.25044 -1.3208)
			(stroke
				(width 0.1524)
				(type default)
			)
			(layer "F.SilkS")
		)
		(fp_line
			(start -0.5842 -1.5494)
			(end -2.25044 -1.5494)
			(stroke
				(width 0.1524)
				(type default)
			)
			(layer "F.SilkS")
		)
		(fp_line
			(start 0.5842 -1.5494)
			(end 0 -0.9652)
			(stroke
				(width 0.1524)
				(type default)
			)
			(layer "F.SilkS")
		)
		(fp_line
			(start 2.0066 -1.5494)
			(end 0.5842 -1.5494)
			(stroke
				(width 0.1524)
				(type default)
			)
			(layer "F.SilkS")
		)
		(fp_line
			(start 2.25044 -1.5494)
			(end 0.5842 -1.5494)
			(stroke
				(width 0.1524)
				(type default)
			)
			(layer "F.SilkS")
		)
		(fp_poly
			(pts
				(xy -3.81 -1.016) (xy -4.36372 -0.719328) (xy -4.36372 -1.344168)
			)
			(stroke
				(width 0)
				(type default)
			)
			(fill yes)
			(layer "F.SilkS")
		)
		(fp_line
			(start -2.25044 1.5494)
			(end 2.25044 1.5494)
			(stroke
				(width 0.1)
				(type default)
			)
			(layer "F.Fab")
		)
		(fp_line
			(start -2.25044 1.5494)
			(end -2.25044 1.12522)
			(stroke
				(width 0.1)
				(type default)
			)
			(layer "F.Fab")
		)
		(fp_line
			(start 2.25044 1.5494)
			(end 2.25044 1.12522)
			(stroke
				(width 0.1)
				(type default)
			)
			(layer "F.Fab")
		)
		(fp_line
			(start 2.25044 1.5494)
			(end 2.25044 -1.5494)
			(stroke
				(width 0.1)
				(type default)
			)
			(layer "F.Fab")
		)
		(fp_line
			(start 2.25044 1.143)
			(end 2.25044 1.0922)
			(stroke
				(width 0.1)
				(type default)
			)
			(layer "F.Fab")
		)
		(fp_line
			(start -3.302 1.12522)
			(end -3.302 -1.12522)
			(stroke
				(width 0.1)
				(type default)
			)
			(layer "F.Fab")
		)
		(fp_line
			(start -2.25044 1.12522)
			(end -3.302 1.12522)
			(stroke
				(width 0.1)
				(type default)
			)
			(layer "F.Fab")
		)
		(fp_line
			(start 2.25044 1.12522)
			(end 3.302 1.12522)
			(stroke
				(width 0.1)
				(type default)
			)
			(layer "F.Fab")
		)
		(fp_line
			(start 3.302 1.12522)
			(end 3.302 -1.12522)
			(stroke
				(width 0.1)
				(type default)
			)
			(layer "F.Fab")
		)
		(fp_line
			(start -3.302 -1.12522)
			(end -2.25044 -1.12522)
			(stroke
				(width 0.1)
				(type default)
			)
			(layer "F.Fab")
		)
		(fp_line
			(start -2.25044 -1.12522)
			(end -2.25044 -1.5494)
			(stroke
				(width 0.1)
				(type default)
			)
			(layer "F.Fab")
		)
		(fp_line
			(start 2.25044 -1.12522)
			(end 2.25044 -1.4986)
			(stroke
				(width 0.1)
				(type default)
			)
			(layer "F.Fab")
		)
		(fp_line
			(start 3.302 -1.12522)
			(end 2.25044 -1.12522)
			(stroke
				(width 0.1)
				(type default)
			)
			(layer "F.Fab")
		)
		(fp_line
			(start -2.25044 -1.5494)
			(end -2.25044 1.5494)
			(stroke
				(width 0.1)
				(type default)
			)
			(layer "F.Fab")
		)
		(fp_line
			(start 2.25044 -1.5494)
			(end -2.25044 -1.5494)
			(stroke
				(width 0.1)
				(type default)
			)
			(layer "F.Fab")
		)
		(fp_poly
			(pts
				(xy -4.36372 -0.719328) (xy -4.36372 -1.344168) (xy -3.81 -1.016)
			)
			(stroke
				(width 0)
				(type default)
			)
			(fill yes)
			(layer "F.Fab")
		)
		(pad "1" smd rect
			(at -2.921 -0.975106 180)
			(size 0.3556 1.4986)
			(layers "F.Cu" "F.Mask" "F.Paste")
			(net "CLK_50M_RMII_R")
		)
		(pad "2" smd rect
			(at -2.921 -0.32512 180)
			(size 0.3556 1.4986)
			(layers "F.Cu" "F.Mask" "F.Paste")
			(net "CLK_50M_EN")
		)
		(pad "3" smd rect
			(at -2.921 0.32512 180)
			(size 0.3556 1.4986)
			(layers "F.Cu" "F.Mask" "F.Paste")
			(net "CLK_50M_BMC_MAC_R")
		)
		(pad "4" smd rect
			(at -2.921 0.975106 180)
			(size 0.3556 1.4986)
			(layers "F.Cu" "F.Mask" "F.Paste")
			(net "GND")
		)
		(pad "5" smd rect
			(at 2.921 0.975106 180)
			(size 0.3556 1.4986)
			(layers "F.Cu" "F.Mask" "F.Paste")
			(net "CLK_50M_NCSI_OCP_1")
		)
		(pad "6" smd rect
			(at 2.921 0.32512 180)
			(size 0.3556 1.4986)
			(layers "F.Cu" "F.Mask" "F.Paste")
			(net "P3V3_AUX")
		)
		(pad "7" smd rect
			(at 2.921 -0.32512 180)
			(size 0.3556 1.4986)
			(layers "F.Cu" "F.Mask" "F.Paste")
			(net "CLK_50M_NCSI_OCP_2")
		)
		(pad "8" smd rect
			(at 2.921 -0.975106 180)
			(size 0.3556 1.4986)
			(layers "F.Cu" "F.Mask" "F.Paste")
			(net "TP_CLK_50M_Y3")
		)
	)
	(footprint ""
		(layer "F.Cu")
		(at 280.67 -426.212 90)
		(property "Reference" "C77"
			(at 0 0 90)
			(layer "F.SilkS")
			(hide yes)
			(effects
				(font
					(size 1.27 1.27)
				)
			)
		)
		(property "Value" ""
			(at 0 0 90)
			(layer "F.Fab")
			(effects
				(font
					(size 1.27 1.27)
				)
			)
		)
		(duplicate_pad_numbers_are_jumpers no)
		(fp_line
			(start 0.7874 -0.4064)
			(end 0.7874 0.4064)
			(stroke
				(width 0.1524)
				(type default)
			)
			(layer "F.SilkS")
		)
		(fp_line
			(start -0.7874 -0.4064)
			(end 0.7874 -0.4064)
			(stroke
				(width 0.1524)
				(type default)
			)
			(layer "F.SilkS")
		)
		(fp_line
			(start 0.7874 0.4064)
			(end -0.7874 0.4064)
			(stroke
				(width 0.1524)
				(type default)
			)
			(layer "F.SilkS")
		)
		(fp_line
			(start -0.7874 0.4064)
			(end -0.7874 -0.4064)
			(stroke
				(width 0.1524)
				(type default)
			)
			(layer "F.SilkS")
		)
		(fp_line
			(start -0.12065 -0.305054)
			(end -0.12065 -0.2794)
			(stroke
				(width 0.1)
				(type default)
			)
			(layer "F.Fab")
		)
		(fp_line
			(start -0.67945 -0.305054)
			(end -0.12065 -0.305054)
			(stroke
				(width 0.1)
				(type default)
			)
			(layer "F.Fab")
		)
		(fp_line
			(start 0.67945 -0.3048)
			(end 0.67945 0.3048)
			(stroke
				(width 0.1)
				(type default)
			)
			(layer "F.Fab")
		)
		(fp_line
			(start 0.12065 -0.3048)
			(end 0.67945 -0.3048)
			(stroke
				(width 0.1)
				(type default)
			)
			(layer "F.Fab")
		)
		(fp_line
			(start 0.12065 -0.2794)
			(end 0.12065 -0.3048)
			(stroke
				(width 0.1)
				(type default)
			)
			(layer "F.Fab")
		)
		(fp_line
			(start -0.12065 -0.2794)
			(end 0.12065 -0.2794)
			(stroke
				(width 0.1)
				(type default)
			)
			(layer "F.Fab")
		)
		(fp_line
			(start 0.120396 0.2794)
			(end -0.12065 0.2794)
			(stroke
				(width 0.1)
				(type default)
			)
			(layer "F.Fab")
		)
		(fp_line
			(start -0.12065 0.2794)
			(end -0.12065 0.3048)
			(stroke
				(width 0.1)
				(type default)
			)
			(layer "F.Fab")
		)
		(fp_line
			(start 0.67945 0.3048)
			(end 0.120396 0.3048)
			(stroke
				(width 0.1)
				(type default)
			)
			(layer "F.Fab")
		)
		(fp_line
			(start 0.120396 0.3048)
			(end 0.120396 0.2794)
			(stroke
				(width 0.1)
				(type default)
			)
			(layer "F.Fab")
		)
		(fp_line
			(start -0.12065 0.3048)
			(end -0.67945 0.3048)
			(stroke
				(width 0.1)
				(type default)
			)
			(layer "F.Fab")
		)
		(fp_line
			(start -0.67945 0.3048)
			(end -0.67945 -0.305054)
			(stroke
				(width 0.1)
				(type default)
			)
			(layer "F.Fab")
		)
		(pad "1" smd circle
			(at -0.40005 0 90)
			(size 0 0)
			(layers "F.Cu" "F.Mask" "F.Paste")
			(net "P3V3_9ZXL045_P0_VDDR")
		)
		(pad "2" smd circle
			(at 0.40005 0 90)
			(size 0 0)
			(layers "F.Cu" "F.Mask" "F.Paste")
			(net "GND")
		)
	)
	(footprint ""
		(layer "F.Cu")
		(at 445.19088 -95.872808 180)
		(property "Reference" "R3601"
			(at 0 0 180)
			(layer "F.SilkS")
			(hide yes)
			(effects
				(font
					(size 1.27 1.27)
				)
			)
		)
		(property "Value" ""
			(at 0 0 180)
			(layer "F.Fab")
			(effects
				(font
					(size 1.27 1.27)
				)
			)
		)
		(duplicate_pad_numbers_are_jumpers no)
		(fp_line
			(start 0.7874 0.4064)
			(end -0.7874 0.4064)
			(stroke
				(width 0.1524)
				(type default)
			)
			(layer "F.SilkS")
		)
		(fp_line
			(start 0.7874 -0.4064)
			(end 0.7874 0.4064)
			(stroke
				(width 0.1524)
				(type default)
			)
			(layer "F.SilkS")
		)
		(fp_line
			(start -0.7874 0.4064)
			(end -0.7874 -0.4064)
			(stroke
				(width 0.1524)
				(type default)
			)
			(layer "F.SilkS")
		)
		(fp_line
			(start -0.7874 -0.4064)
			(end 0.7874 -0.4064)
			(stroke
				(width 0.1524)
				(type default)
			)
			(layer "F.SilkS")
		)
		(fp_line
			(start 0.67945 0.3048)
			(end 0.120396 0.3048)
			(stroke
				(width 0.1)
				(type default)
			)
			(layer "F.Fab")
		)
		(fp_line
			(start 0.67945 -0.3048)
			(end 0.67945 0.3048)
			(stroke
				(width 0.1)
				(type default)
			)
			(layer "F.Fab")
		)
		(fp_line
			(start 0.12065 -0.2794)
			(end 0.12065 -0.3048)
			(stroke
				(width 0.1)
				(type default)
			)
			(layer "F.Fab")
		)
		(fp_line
			(start 0.12065 -0.3048)
			(end 0.67945 -0.3048)
			(stroke
				(width 0.1)
				(type default)
			)
			(layer "F.Fab")
		)
		(fp_line
			(start 0.120396 0.3048)
			(end 0.120396 0.2794)
			(stroke
				(width 0.1)
				(type default)
			)
			(layer "F.Fab")
		)
		(fp_line
			(start 0.120396 0.2794)
			(end -0.12065 0.2794)
			(stroke
				(width 0.1)
				(type default)
			)
			(layer "F.Fab")
		)
		(fp_line
			(start -0.12065 0.3048)
			(end -0.67945 0.3048)
			(stroke
				(width 0.1)
				(type default)
			)
			(layer "F.Fab")
		)
		(fp_line
			(start -0.12065 0.2794)
			(end -0.12065 0.3048)
			(stroke
				(width 0.1)
				(type default)
			)
			(layer "F.Fab")
		)
		(fp_line
			(start -0.12065 -0.2794)
			(end 0.12065 -0.2794)
			(stroke
				(width 0.1)
				(type default)
			)
			(layer "F.Fab")
		)
		(fp_line
			(start -0.12065 -0.305054)
			(end -0.12065 -0.2794)
			(stroke
				(width 0.1)
				(type default)
			)
			(layer "F.Fab")
		)
		(fp_line
			(start -0.67945 0.3048)
			(end -0.67945 -0.305054)
			(stroke
				(width 0.1)
				(type default)
			)
			(layer "F.Fab")
		)
		(fp_line
			(start -0.67945 -0.305054)
			(end -0.12065 -0.305054)
			(stroke
				(width 0.1)
				(type default)
			)
			(layer "F.Fab")
		)
		(pad "1" smd circle
			(at -0.40005 0 180)
			(size 0 0)
			(layers "F.Cu" "F.Mask" "F.Paste")
			(net "SMB_INA230_1_3V3AUX_SDA_R")
		)
		(pad "2" smd circle
			(at 0.40005 0 180)
			(size 0 0)
			(layers "F.Cu" "F.Mask" "F.Paste")
			(net "SMB_INA230_1_3V3AUX_SDA_R1")
		)
	)
	(footprint ""
		(layer "F.Cu")
		(at 365.701326 -45.267118 -90)
		(property "Reference" "R813"
			(at 0 0 270)
			(layer "F.SilkS")
			(hide yes)
			(effects
				(font
					(size 1.27 1.27)
				)
			)
		)
		(property "Value" ""
			(at 0 0 270)
			(layer "F.Fab")
			(effects
				(font
					(size 1.27 1.27)
				)
			)
		)
		(duplicate_pad_numbers_are_jumpers no)
		(fp_line
			(start -0.7874 0.4064)
			(end -0.7874 -0.4064)
			(stroke
				(width 0.1524)
				(type default)
			)
			(layer "F.SilkS")
		)
		(fp_line
			(start 0.7874 0.4064)
			(end -0.7874 0.4064)
			(stroke
				(width 0.1524)
				(type default)
			)
			(layer "F.SilkS")
		)
		(fp_line
			(start -0.7874 -0.4064)
			(end 0.7874 -0.4064)
			(stroke
				(width 0.1524)
				(type default)
			)
			(layer "F.SilkS")
		)
		(fp_line
			(start 0.7874 -0.4064)
			(end 0.7874 0.4064)
			(stroke
				(width 0.1524)
				(type default)
			)
			(layer "F.SilkS")
		)
		(fp_line
			(start -0.67945 0.3048)
			(end -0.67945 -0.305054)
			(stroke
				(width 0.1)
				(type default)
			)
			(layer "F.Fab")
		)
		(fp_line
			(start -0.12065 0.3048)
			(end -0.67945 0.3048)
			(stroke
				(width 0.1)
				(type default)
			)
			(layer "F.Fab")
		)
		(fp_line
			(start 0.120396 0.3048)
			(end 0.120396 0.2794)
			(stroke
				(width 0.1)
				(type default)
			)
			(layer "F.Fab")
		)
		(fp_line
			(start 0.67945 0.3048)
			(end 0.120396 0.3048)
			(stroke
				(width 0.1)
				(type default)
			)
			(layer "F.Fab")
		)
		(fp_line
			(start -0.12065 0.2794)
			(end -0.12065 0.3048)
			(stroke
				(width 0.1)
				(type default)
			)
			(layer "F.Fab")
		)
		(fp_line
			(start 0.120396 0.2794)
			(end -0.12065 0.2794)
			(stroke
				(width 0.1)
				(type default)
			)
			(layer "F.Fab")
		)
		(fp_line
			(start -0.12065 -0.2794)
			(end 0.12065 -0.2794)
			(stroke
				(width 0.1)
				(type default)
			)
			(layer "F.Fab")
		)
		(fp_line
			(start 0.12065 -0.2794)
			(end 0.12065 -0.3048)
			(stroke
				(width 0.1)
				(type default)
			)
			(layer "F.Fab")
		)
		(fp_line
			(start 0.12065 -0.3048)
			(end 0.67945 -0.3048)
			(stroke
				(width 0.1)
				(type default)
			)
			(layer "F.Fab")
		)
		(fp_line
			(start 0.67945 -0.3048)
			(end 0.67945 0.3048)
			(stroke
				(width 0.1)
				(type default)
			)
			(layer "F.Fab")
		)
		(fp_line
			(start -0.67945 -0.305054)
			(end -0.12065 -0.305054)
			(stroke
				(width 0.1)
				(type default)
			)
			(layer "F.Fab")
		)
		(fp_line
			(start -0.12065 -0.305054)
			(end -0.12065 -0.2794)
			(stroke
				(width 0.1)
				(type default)
			)
			(layer "F.Fab")
		)
		(pad "1" smd circle
			(at -0.40005 0 270)
			(size 0 0)
			(layers "F.Cu" "F.Mask" "F.Paste")
			(net "PVDD18_S5_P0")
		)
		(pad "2" smd circle
			(at 0.40005 0 270)
			(size 0 0)
			(layers "F.Cu" "F.Mask" "F.Paste")
			(net "UART_CPU0_UART0_RX")
		)
	)
	(footprint ""
		(layer "F.Cu")
		(at 15.288006 -105.53573 90)
		(property "Reference" "R2790"
			(at 0 0 90)
			(layer "F.SilkS")
			(hide yes)
			(effects
				(font
					(size 1.27 1.27)
				)
			)
		)
		(property "Value" ""
			(at 0 0 90)
			(layer "F.Fab")
			(effects
				(font
					(size 1.27 1.27)
				)
			)
		)
		(duplicate_pad_numbers_are_jumpers no)
		(fp_line
			(start 0.7874 -0.4064)
			(end 0.7874 0.4064)
			(stroke
				(width 0.1524)
				(type default)
			)
			(layer "F.SilkS")
		)
		(fp_line
			(start -0.7874 -0.4064)
			(end 0.7874 -0.4064)
			(stroke
				(width 0.1524)
				(type default)
			)
			(layer "F.SilkS")
		)
		(fp_line
			(start 0.7874 0.4064)
			(end -0.7874 0.4064)
			(stroke
				(width 0.1524)
				(type default)
			)
			(layer "F.SilkS")
		)
		(fp_line
			(start -0.7874 0.4064)
			(end -0.7874 -0.4064)
			(stroke
				(width 0.1524)
				(type default)
			)
			(layer "F.SilkS")
		)
		(fp_line
			(start -0.12065 -0.305054)
			(end -0.12065 -0.2794)
			(stroke
				(width 0.1)
				(type default)
			)
			(layer "F.Fab")
		)
		(fp_line
			(start -0.67945 -0.305054)
			(end -0.12065 -0.305054)
			(stroke
				(width 0.1)
				(type default)
			)
			(layer "F.Fab")
		)
		(fp_line
			(start 0.67945 -0.3048)
			(end 0.67945 0.3048)
			(stroke
				(width 0.1)
				(type default)
			)
			(layer "F.Fab")
		)
		(fp_line
			(start 0.12065 -0.3048)
			(end 0.67945 -0.3048)
			(stroke
				(width 0.1)
				(type default)
			)
			(layer "F.Fab")
		)
		(fp_line
			(start 0.12065 -0.2794)
			(end 0.12065 -0.3048)
			(stroke
				(width 0.1)
				(type default)
			)
			(layer "F.Fab")
		)
		(fp_line
			(start -0.12065 -0.2794)
			(end 0.12065 -0.2794)
			(stroke
				(width 0.1)
				(type default)
			)
			(layer "F.Fab")
		)
		(fp_line
			(start 0.120396 0.2794)
			(end -0.12065 0.2794)
			(stroke
				(width 0.1)
				(type default)
			)
			(layer "F.Fab")
		)
		(fp_line
			(start -0.12065 0.2794)
			(end -0.12065 0.3048)
			(stroke
				(width 0.1)
				(type default)
			)
			(layer "F.Fab")
		)
		(fp_line
			(start 0.67945 0.3048)
			(end 0.120396 0.3048)
			(stroke
				(width 0.1)
				(type default)
			)
			(layer "F.Fab")
		)
		(fp_line
			(start 0.120396 0.3048)
			(end 0.120396 0.2794)
			(stroke
				(width 0.1)
				(type default)
			)
			(layer "F.Fab")
		)
		(fp_line
			(start -0.12065 0.3048)
			(end -0.67945 0.3048)
			(stroke
				(width 0.1)
				(type default)
			)
			(layer "F.Fab")
		)
		(fp_line
			(start -0.67945 0.3048)
			(end -0.67945 -0.305054)
			(stroke
				(width 0.1)
				(type default)
			)
			(layer "F.Fab")
		)
		(pad "1" smd rect
			(at -0.40005 0 270)
			(size 0.4572 0.508)
			(layers "F.Cu" "F.Mask" "F.Paste")
			(net "USB2_HOST_BMC_B_DP")
		)
		(pad "2" smd rect
			(at 0.40005 0 270)
			(size 0.4572 0.508)
			(layers "F.Cu" "F.Mask" "F.Paste")
			(net "USB2_HOST_BMC_B_BUF_DP")
		)
	)
)
